(kicad_pcb
	(version 20260206)
	(generator "pcbnew")
	(generator_version "10.0")
	(general
		(thickness 1.6)
		(legacy_teardrops no)
	)
	(paper "A4")
	(title_block
		(title "baseboard — 13948-1b.1110WZS1818.brd")
		(comment 1 "Honey Badger (Wiwynn) / footprints 1451-1457 of 2523")
	)
	(layers
		(0 "F.Cu" signal "TOP")
		(4 "In1.Cu" signal "L2GND")
		(6 "In2.Cu" signal "L3")
		(8 "In3.Cu" signal "L4VCC")
		(10 "In4.Cu" signal "L5VCC")
		(12 "In5.Cu" signal "L6")
		(14 "In6.Cu" signal "L7GND")
		(2 "B.Cu" signal "BOTTOM")
		(9 "F.Adhes" user "F.Adhesive")
		(11 "B.Adhes" user "B.Adhesive")
		(13 "F.Paste" user "Package Geometry/Pastemask Top")
		(15 "B.Paste" user "Package Geometry/Pastemask Bottom")
		(5 "F.SilkS" user "Ref Des/Silkscreen Top")
		(7 "B.SilkS" user "Ref Des/Silkscreen Bottom")
		(1 "F.Mask" user "Board Geometry/Soldermask Top")
		(3 "B.Mask" user "Board Geometry/Soldermask Bottom")
		(17 "Dwgs.User" user "User.Drawings")
		(19 "Cmts.User" user "User.Comments")
		(21 "Eco1.User" user "User.Eco1")
		(23 "Eco2.User" user "User.Eco2")
		(25 "Edge.Cuts" user "Board Geometry/Outline")
		(27 "Margin" user)
		(31 "F.CrtYd" user "Package Geometry/Place Bound Top")
		(29 "B.CrtYd" user "Package Geometry/Place Bound Bottom")
		(35 "F.Fab" user "Ref Des/Assembly Top")
		(33 "B.Fab" user "Ref Des/Assembly Bottom")
	)
	(footprint ""
		(layer "F.Cu")
		(at 60.706 -108.458 90)
		(property "Reference" "SR826"
			(at 0 0 90)
			(layer "F.SilkS")
			(hide yes)
			(effects
				(font
					(size 1.27 1.27)
				)
			)
		)
		(property "Value" "4K75R2F-1-GP"
			(at 0.064008 -3.993896 90)
			(unlocked yes)
			(layer "F.Fab")
			(hide yes)
			(effects
				(font
					(size 1.016 1.016)
					(thickness 0.1524)
				)
			)
		)
		(property "Device Type" "R402H16"
			(at 0.064008 -5.517896 90)
			(unlocked yes)
			(layer "F.Fab")
			(hide yes)
			(effects
				(font
					(size 1.016 1.016)
					(thickness 0.1524)
				)
			)
		)
		(duplicate_pad_numbers_are_jumpers no)
		(fp_line
			(start 0.508 -0.9398)
			(end -0.508 -0.9398)
			(stroke
				(width 0.1524)
				(type default)
			)
			(layer "F.SilkS")
		)
		(fp_line
			(start -0.508 -0.9398)
			(end -0.508 0.9398)
			(stroke
				(width 0.1524)
				(type default)
			)
			(layer "F.SilkS")
		)
		(fp_rect
			(start -0.508 0.9398)
			(end 0.508 -0.9398)
			(stroke
				(width 0)
				(type default)
			)
			(fill no)
			(layer "F.CrtYd")
		)
		(fp_rect
			(start -0.508 0.9398)
			(end 0.508 -0.9398)
			(stroke
				(width 0)
				(type default)
			)
			(fill no)
			(layer "F.Fab")
		)
		(pad "1" smd custom
			(at 0 -0.4445 90)
			(size 0.1397 0.1397)
			(layers "F.Cu" "F.Mask" "F.Paste")
			(net "P1V8_E")
			(options
				(clearance outline)
				(anchor circle)
			)
			(primitives
				(gr_poly
					(pts
						(arc
							(start -0.1778 -0.2794)
							(mid -0.249642 -0.249642)
							(end -0.2794 -0.1778)
						)
						(arc
							(start -0.2794 0.1778)
							(mid -0.249642 0.249642)
							(end -0.1778 0.2794)
						)
						(arc
							(start 0.1778 0.2794)
							(mid 0.249642 0.249642)
							(end 0.2794 0.1778)
						)
						(arc
							(start 0.2794 -0.1778)
							(mid 0.249642 -0.249642)
							(end 0.1778 -0.2794)
						)
					)
					(width 0)
					(fill yes)
				)
			)
		)
		(pad "2" smd custom
			(at 0 0.4445 90)
			(size 0.1397 0.1397)
			(layers "F.Cu" "F.Mask" "F.Paste")
			(net "EXP_FW_DET_BOARD_VER_0")
			(options
				(clearance outline)
				(anchor circle)
			)
			(primitives
				(gr_poly
					(pts
						(arc
							(start -0.1778 -0.2794)
							(mid -0.249642 -0.249642)
							(end -0.2794 -0.1778)
						)
						(arc
							(start -0.2794 0.1778)
							(mid -0.249642 0.249642)
							(end -0.1778 0.2794)
						)
						(arc
							(start 0.1778 0.2794)
							(mid 0.249642 0.249642)
							(end 0.2794 0.1778)
						)
						(arc
							(start 0.2794 -0.1778)
							(mid 0.249642 -0.249642)
							(end 0.1778 -0.2794)
						)
					)
					(width 0)
					(fill yes)
				)
			)
		)
	)
	(footprint ""
		(layer "F.Cu")
		(at 95.89897 -79.375 -90)
		(property "Reference" "SR815"
			(at 0 0 270)
			(layer "F.SilkS")
			(hide yes)
			(effects
				(font
					(size 1.27 1.27)
				)
			)
		)
		(property "Value" "1KR2F-3-GP"
			(at 0.064008 -3.993896 270)
			(unlocked yes)
			(layer "F.Fab")
			(hide yes)
			(effects
				(font
					(size 1.016 1.016)
					(thickness 0.1524)
				)
			)
		)
		(property "Device Type" "R402H16"
			(at 0.064008 -5.517896 270)
			(unlocked yes)
			(layer "F.Fab")
			(hide yes)
			(effects
				(font
					(size 1.016 1.016)
					(thickness 0.1524)
				)
			)
		)
		(duplicate_pad_numbers_are_jumpers no)
		(fp_line
			(start -0.508 -0.9398)
			(end -0.508 0.9398)
			(stroke
				(width 0.1524)
				(type default)
			)
			(layer "F.SilkS")
		)
		(fp_line
			(start 0.508 -0.9398)
			(end -0.508 -0.9398)
			(stroke
				(width 0.1524)
				(type default)
			)
			(layer "F.SilkS")
		)
		(fp_rect
			(start -0.508 0.9398)
			(end 0.508 -0.9398)
			(stroke
				(width 0)
				(type default)
			)
			(fill no)
			(layer "F.CrtYd")
		)
		(fp_rect
			(start -0.508 0.9398)
			(end 0.508 -0.9398)
			(stroke
				(width 0)
				(type default)
			)
			(fill no)
			(layer "F.Fab")
		)
		(pad "1" smd custom
			(at 0 -0.4445 270)
			(size 0.1397 0.1397)
			(layers "F.Cu" "F.Mask" "F.Paste")
			(net "TMUX_EN")
			(options
				(clearance outline)
				(anchor circle)
			)
			(primitives
				(gr_poly
					(pts
						(arc
							(start -0.1778 -0.2794)
							(mid -0.249642 -0.249642)
							(end -0.2794 -0.1778)
						)
						(arc
							(start -0.2794 0.1778)
							(mid -0.249642 0.249642)
							(end -0.1778 0.2794)
						)
						(arc
							(start 0.1778 0.2794)
							(mid 0.249642 0.249642)
							(end 0.2794 0.1778)
						)
						(arc
							(start 0.2794 -0.1778)
							(mid 0.249642 -0.249642)
							(end 0.1778 -0.2794)
						)
					)
					(width 0)
					(fill yes)
				)
			)
		)
		(pad "2" smd custom
			(at 0 0.4445 270)
			(size 0.1397 0.1397)
			(layers "F.Cu" "F.Mask" "F.Paste")
			(net "P1V8_E")
			(options
				(clearance outline)
				(anchor circle)
			)
			(primitives
				(gr_poly
					(pts
						(arc
							(start -0.1778 -0.2794)
							(mid -0.249642 -0.249642)
							(end -0.2794 -0.1778)
						)
						(arc
							(start -0.2794 0.1778)
							(mid -0.249642 0.249642)
							(end -0.1778 0.2794)
						)
						(arc
							(start 0.1778 0.2794)
							(mid 0.249642 0.249642)
							(end 0.2794 0.1778)
						)
						(arc
							(start 0.2794 -0.1778)
							(mid 0.249642 -0.249642)
							(end 0.1778 -0.2794)
						)
					)
					(width 0)
					(fill yes)
				)
			)
		)
	)
	(footprint ""
		(layer "F.Cu")
		(at 99.568 -10.795 180)
		(property "Reference" "SR715"
			(at 0 0 180)
			(layer "F.SilkS")
			(hide yes)
			(effects
				(font
					(size 1.27 1.27)
				)
			)
		)
		(property "Value" "D51R3F-2-GP"
			(at -0.0254 -2.5146 180)
			(unlocked yes)
			(layer "F.Fab")
			(hide yes)
			(effects
				(font
					(size 1.016 1.016)
					(thickness 0.1524)
				)
			)
		)
		(property "Device Type" "R603H22"
			(at -0.0254 -4.0386 180)
			(unlocked yes)
			(layer "F.Fab")
			(hide yes)
			(effects
				(font
					(size 1.016 1.016)
					(thickness 0.1524)
				)
			)
		)
		(duplicate_pad_numbers_are_jumpers no)
		(fp_line
			(start 0.2032 0)
			(end 0.4826 0)
			(stroke
				(width 0.2032)
				(type default)
			)
			(layer "F.SilkS")
		)
		(fp_line
			(start -0.4826 0)
			(end -0.2032 0)
			(stroke
				(width 0.2032)
				(type default)
			)
			(layer "F.SilkS")
		)
		(fp_rect
			(start -0.5842 1.3335)
			(end 0.5842 -1.3335)
			(stroke
				(width 0)
				(type default)
			)
			(fill no)
			(layer "F.CrtYd")
		)
		(fp_rect
			(start -0.5842 1.3335)
			(end 0.5842 -1.3335)
			(stroke
				(width 0)
				(type default)
			)
			(fill no)
			(layer "F.Fab")
		)
		(pad "1" smd custom
			(at 0 -0.762 180)
			(size 0.2159 0.2159)
			(layers "F.Cu" "F.Mask" "F.Paste")
			(net "P0V955_C")
			(options
				(clearance outline)
				(anchor circle)
			)
			(primitives
				(gr_poly
					(pts
						(arc
							(start -0.3302 -0.4318)
							(mid -0.402042 -0.402042)
							(end -0.4318 -0.3302)
						)
						(arc
							(start -0.4318 0.3302)
							(mid -0.402042 0.402042)
							(end -0.3302 0.4318)
						)
						(arc
							(start 0.3302 0.4318)
							(mid 0.402042 0.402042)
							(end 0.4318 0.3302)
						)
						(arc
							(start 0.4318 -0.3302)
							(mid 0.402042 -0.402042)
							(end 0.3302 -0.4318)
						)
					)
					(width 0)
					(fill yes)
				)
			)
		)
		(pad "2" smd custom
			(at 0 0.762 180)
			(size 0.2159 0.2159)
			(layers "F.Cu" "F.Mask" "F.Paste")
			(net "PCE_AVDD")
			(options
				(clearance outline)
				(anchor circle)
			)
			(primitives
				(gr_poly
					(pts
						(arc
							(start -0.3302 -0.4318)
							(mid -0.402042 -0.402042)
							(end -0.4318 -0.3302)
						)
						(arc
							(start -0.4318 0.3302)
							(mid -0.402042 0.402042)
							(end -0.3302 0.4318)
						)
						(arc
							(start 0.3302 0.4318)
							(mid 0.402042 0.402042)
							(end 0.4318 0.3302)
						)
						(arc
							(start 0.4318 -0.3302)
							(mid 0.402042 -0.402042)
							(end 0.3302 -0.4318)
						)
					)
					(width 0)
					(fill yes)
				)
			)
		)
	)
	(footprint ""
		(layer "F.Cu")
		(at 35.383216 -205.28788 90)
		(property "Reference" "R5310"
			(at 0 0 90)
			(layer "F.SilkS")
			(hide yes)
			(effects
				(font
					(size 1.27 1.27)
				)
			)
		)
		(property "Value" "0R2J-2-GP"
			(at 0.064008 -3.993896 90)
			(unlocked yes)
			(layer "F.Fab")
			(hide yes)
			(effects
				(font
					(size 1.016 1.016)
					(thickness 0.1524)
				)
			)
		)
		(property "Device Type" "R402H16"
			(at 0.064008 -5.517896 90)
			(unlocked yes)
			(layer "F.Fab")
			(hide yes)
			(effects
				(font
					(size 1.016 1.016)
					(thickness 0.1524)
				)
			)
		)
		(duplicate_pad_numbers_are_jumpers no)
		(fp_line
			(start 0.508 -0.9398)
			(end -0.508 -0.9398)
			(stroke
				(width 0.1524)
				(type default)
			)
			(layer "F.SilkS")
		)
		(fp_line
			(start -0.508 -0.9398)
			(end -0.508 0.9398)
			(stroke
				(width 0.1524)
				(type default)
			)
			(layer "F.SilkS")
		)
		(fp_rect
			(start -0.508 0.9398)
			(end 0.508 -0.9398)
			(stroke
				(width 0)
				(type default)
			)
			(fill no)
			(layer "F.CrtYd")
		)
		(fp_rect
			(start -0.508 0.9398)
			(end 0.508 -0.9398)
			(stroke
				(width 0)
				(type default)
			)
			(fill no)
			(layer "F.Fab")
		)
		(pad "1" smd custom
			(at 0 -0.4445 90)
			(size 0.1397 0.1397)
			(layers "F.Cu" "F.Mask" "F.Paste")
			(net "VOL_SEN_SCL_U17")
			(options
				(clearance outline)
				(anchor circle)
			)
			(primitives
				(gr_poly
					(pts
						(arc
							(start -0.1778 -0.2794)
							(mid -0.249642 -0.249642)
							(end -0.2794 -0.1778)
						)
						(arc
							(start -0.2794 0.1778)
							(mid -0.249642 0.249642)
							(end -0.1778 0.2794)
						)
						(arc
							(start 0.1778 0.2794)
							(mid 0.249642 0.249642)
							(end 0.2794 0.1778)
						)
						(arc
							(start 0.2794 -0.1778)
							(mid 0.249642 -0.249642)
							(end 0.1778 -0.2794)
						)
					)
					(width 0)
					(fill yes)
				)
			)
		)
		(pad "2" smd custom
			(at 0 0.4445 90)
			(size 0.1397 0.1397)
			(layers "F.Cu" "F.Mask" "F.Paste")
			(net "BMC_I2C_SCL_10")
			(options
				(clearance outline)
				(anchor circle)
			)
			(primitives
				(gr_poly
					(pts
						(arc
							(start -0.1778 -0.2794)
							(mid -0.249642 -0.249642)
							(end -0.2794 -0.1778)
						)
						(arc
							(start -0.2794 0.1778)
							(mid -0.249642 0.249642)
							(end -0.1778 0.2794)
						)
						(arc
							(start 0.1778 0.2794)
							(mid 0.249642 0.249642)
							(end 0.2794 0.1778)
						)
						(arc
							(start 0.2794 -0.1778)
							(mid 0.249642 -0.249642)
							(end 0.1778 -0.2794)
						)
					)
					(width 0)
					(fill yes)
				)
			)
		)
	)
	(footprint ""
		(layer "F.Cu")
		(at 315.468 -118.618)
		(property "Reference" "PR31"
			(at 0 0 0)
			(layer "F.SilkS")
			(hide yes)
			(effects
				(font
					(size 1.27 1.27)
				)
			)
		)
		(property "Value" "73K2R2F-GP"
			(at 0.064008 -3.993896 0)
			(unlocked yes)
			(layer "F.Fab")
			(hide yes)
			(effects
				(font
					(size 1.016 1.016)
					(thickness 0.1524)
				)
			)
		)
		(property "Device Type" "R402H16"
			(at 0.064008 -5.517896 0)
			(unlocked yes)
			(layer "F.Fab")
			(hide yes)
			(effects
				(font
					(size 1.016 1.016)
					(thickness 0.1524)
				)
			)
		)
		(duplicate_pad_numbers_are_jumpers no)
		(fp_line
			(start -0.508 -0.9398)
			(end -0.508 0.9398)
			(stroke
				(width 0.1524)
				(type default)
			)
			(layer "F.SilkS")
		)
		(fp_line
			(start 0.508 -0.9398)
			(end -0.508 -0.9398)
			(stroke
				(width 0.1524)
				(type default)
			)
			(layer "F.SilkS")
		)
		(fp_rect
			(start -0.508 0.9398)
			(end 0.508 -0.9398)
			(stroke
				(width 0)
				(type default)
			)
			(fill no)
			(layer "F.CrtYd")
		)
		(fp_rect
			(start -0.508 0.9398)
			(end 0.508 -0.9398)
			(stroke
				(width 0)
				(type default)
			)
			(fill no)
			(layer "F.Fab")
		)
		(pad "1" smd custom
			(at 0 -0.4445)
			(size 0.1397 0.1397)
			(layers "F.Cu" "F.Mask" "F.Paste")
			(net "AGND_P3V3_STBY")
			(options
				(clearance outline)
				(anchor circle)
			)
			(primitives
				(gr_poly
					(pts
						(arc
							(start -0.1778 -0.2794)
							(mid -0.249642 -0.249642)
							(end -0.2794 -0.1778)
						)
						(arc
							(start -0.2794 0.1778)
							(mid -0.249642 0.249642)
							(end -0.1778 0.2794)
						)
						(arc
							(start 0.1778 0.2794)
							(mid 0.249642 0.249642)
							(end 0.2794 0.1778)
						)
						(arc
							(start 0.2794 -0.1778)
							(mid 0.249642 -0.249642)
							(end 0.1778 -0.2794)
						)
					)
					(width 0)
					(fill yes)
				)
			)
		)
		(pad "2" smd custom
			(at 0 0.4445)
			(size 0.1397 0.1397)
			(layers "F.Cu" "F.Mask" "F.Paste")
			(net "P3V3_STBY_TRIP")
			(options
				(clearance outline)
				(anchor circle)
			)
			(primitives
				(gr_poly
					(pts
						(arc
							(start -0.1778 -0.2794)
							(mid -0.249642 -0.249642)
							(end -0.2794 -0.1778)
						)
						(arc
							(start -0.2794 0.1778)
							(mid -0.249642 0.249642)
							(end -0.1778 0.2794)
						)
						(arc
							(start 0.1778 0.2794)
							(mid 0.249642 0.249642)
							(end 0.2794 0.1778)
						)
						(arc
							(start 0.2794 -0.1778)
							(mid 0.249642 -0.249642)
							(end 0.1778 -0.2794)
						)
					)
					(width 0)
					(fill yes)
				)
			)
		)
	)
	(footprint ""
		(layer "F.Cu")
		(at 86.614 -27.18816 180)
		(property "Reference" "SR581"
			(at 0 0 180)
			(layer "F.SilkS")
			(hide yes)
			(effects
				(font
					(size 1.27 1.27)
				)
			)
		)
		(property "Value" "0R2J-2-GP"
			(at 0.064008 -3.993896 180)
			(unlocked yes)
			(layer "F.Fab")
			(hide yes)
			(effects
				(font
					(size 1.016 1.016)
					(thickness 0.1524)
				)
			)
		)
		(property "Device Type" "R402H16"
			(at 0.064008 -5.517896 180)
			(unlocked yes)
			(layer "F.Fab")
			(hide yes)
			(effects
				(font
					(size 1.016 1.016)
					(thickness 0.1524)
				)
			)
		)
		(duplicate_pad_numbers_are_jumpers no)
		(fp_line
			(start 0.508 -0.9398)
			(end -0.508 -0.9398)
			(stroke
				(width 0.1524)
				(type default)
			)
			(layer "F.SilkS")
		)
		(fp_line
			(start -0.508 -0.9398)
			(end -0.508 0.9398)
			(stroke
				(width 0.1524)
				(type default)
			)
			(layer "F.SilkS")
		)
		(fp_rect
			(start -0.508 0.9398)
			(end 0.508 -0.9398)
			(stroke
				(width 0)
				(type default)
			)
			(fill no)
			(layer "F.CrtYd")
		)
		(fp_rect
			(start -0.508 0.9398)
			(end 0.508 -0.9398)
			(stroke
				(width 0)
				(type default)
			)
			(fill no)
			(layer "F.Fab")
		)
		(pad "1" smd custom
			(at 0 -0.4445 180)
			(size 0.1397 0.1397)
			(layers "F.Cu" "F.Mask" "F.Paste")
			(net "CLK_100M_PCIE_SAS_C_P")
			(options
				(clearance outline)
				(anchor circle)
			)
			(primitives
				(gr_poly
					(pts
						(arc
							(start -0.1778 -0.2794)
							(mid -0.249642 -0.249642)
							(end -0.2794 -0.1778)
						)
						(arc
							(start -0.2794 0.1778)
							(mid -0.249642 0.249642)
							(end -0.1778 0.2794)
						)
						(arc
							(start 0.1778 0.2794)
							(mid 0.249642 0.249642)
							(end 0.2794 0.1778)
						)
						(arc
							(start 0.2794 -0.1778)
							(mid 0.249642 -0.249642)
							(end 0.1778 -0.2794)
						)
					)
					(width 0)
					(fill yes)
				)
			)
		)
		(pad "2" smd custom
			(at 0 0.4445 180)
			(size 0.1397 0.1397)
			(layers "F.Cu" "F.Mask" "F.Paste")
			(net "CLK_100M_PCIE_P")
			(options
				(clearance outline)
				(anchor circle)
			)
			(primitives
				(gr_poly
					(pts
						(arc
							(start -0.1778 -0.2794)
							(mid -0.249642 -0.249642)
							(end -0.2794 -0.1778)
						)
						(arc
							(start -0.2794 0.1778)
							(mid -0.249642 0.249642)
							(end -0.1778 0.2794)
						)
						(arc
							(start 0.1778 0.2794)
							(mid 0.249642 0.249642)
							(end 0.2794 0.1778)
						)
						(arc
							(start 0.2794 -0.1778)
							(mid 0.249642 -0.249642)
							(end 0.1778 -0.2794)
						)
					)
					(width 0)
					(fill yes)
				)
			)
		)
	)
	(footprint ""
		(layer "F.Cu")
		(at 53.975 -204.343 180)
		(property "Reference" "R690"
			(at 0 0 180)
			(layer "F.SilkS")
			(hide yes)
			(effects
				(font
					(size 1.27 1.27)
				)
			)
		)
		(property "Value" "10KR3F-L-GP"
			(at -0.0254 -2.5146 180)
			(unlocked yes)
			(layer "F.Fab")
			(hide yes)
			(effects
				(font
					(size 1.016 1.016)
					(thickness 0.1524)
				)
			)
		)
		(property "Device Type" "R603H22"
			(at -0.0254 -4.0386 180)
			(unlocked yes)
			(layer "F.Fab")
			(hide yes)
			(effects
				(font
					(size 1.016 1.016)
					(thickness 0.1524)
				)
			)
		)
		(duplicate_pad_numbers_are_jumpers no)
		(fp_line
			(start 0.2032 0)
			(end 0.4826 0)
			(stroke
				(width 0.2032)
				(type default)
			)
			(layer "F.SilkS")
		)
		(fp_line
			(start -0.4826 0)
			(end -0.2032 0)
			(stroke
				(width 0.2032)
				(type default)
			)
			(layer "F.SilkS")
		)
		(fp_rect
			(start -0.5842 1.3335)
			(end 0.5842 -1.3335)
			(stroke
				(width 0)
				(type default)
			)
			(fill no)
			(layer "F.CrtYd")
		)
		(fp_rect
			(start -0.5842 1.3335)
			(end 0.5842 -1.3335)
			(stroke
				(width 0)
				(type default)
			)
			(fill no)
			(layer "F.Fab")
		)
		(pad "1" smd custom
			(at 0 -0.762 180)
			(size 0.2159 0.2159)
			(layers "F.Cu" "F.Mask" "F.Paste")
			(net "P12V_PCIE")
			(options
				(clearance outline)
				(anchor circle)
			)
			(primitives
				(gr_poly
					(pts
						(arc
							(start -0.3302 -0.4318)
							(mid -0.402042 -0.402042)
							(end -0.4318 -0.3302)
						)
						(arc
							(start -0.4318 0.3302)
							(mid -0.402042 0.402042)
							(end -0.3302 0.4318)
						)
						(arc
							(start 0.3302 0.4318)
							(mid 0.402042 0.402042)
							(end 0.4318 0.3302)
						)
						(arc
							(start 0.4318 -0.3302)
							(mid 0.402042 -0.402042)
							(end 0.3302 -0.4318)
						)
					)
					(width 0)
					(fill yes)
				)
			)
		)
		(pad "2" smd custom
			(at 0 0.762 180)
			(size 0.2159 0.2159)
			(layers "F.Cu" "F.Mask" "F.Paste")
			(net "MATED_P12V_EN")
			(options
				(clearance outline)
				(anchor circle)
			)
			(primitives
				(gr_poly
					(pts
						(arc
							(start -0.3302 -0.4318)
							(mid -0.402042 -0.402042)
							(end -0.4318 -0.3302)
						)
						(arc
							(start -0.4318 0.3302)
							(mid -0.402042 0.402042)
							(end -0.3302 0.4318)
						)
						(arc
							(start 0.3302 0.4318)
							(mid 0.402042 0.402042)
							(end 0.4318 0.3302)
						)
						(arc
							(start 0.4318 -0.3302)
							(mid 0.402042 -0.402042)
							(end 0.3302 -0.4318)
						)
					)
					(width 0)
					(fill yes)
				)
			)
		)
	)
)
